# T6G (Grand Teton) — schematic netlist excerpt (pin names and nets, part order shuffled) for the footprints in the layout excerpt that follows; sources: Cadence DE-HDL packaged netlist, KiCad conversion of 04192023_DAF0TMB3IC0_F0TG_MB_C_brd_V02_OCP.brd

J100  SCONN288_DDR506112002KQ  IO  pkg DDR288S_1-1VXC  page 106
  VIN_BULK0  = P12V_MEM_CPU1
  RFU0  = NC
  VIN_MGMT  = P3V3_AUX
  HSCL  = I3C_SPD_DDRI_CPU1_SCL
  HSDA  = I3C_SPD_DDRI_CPU1_SDA
  VSS0  = GND
  DQ0_A  = M_I_CPU1_SA_DQ<0>
  VSS1  = GND
  DQ1_A  = M_I_CPU1_SA_DQ<1>
  VSS2  = GND
  DQS0_A_T  = M_I_CPU1_SA_DQS_DP<0>
  DQS0_A_C  = M_I_CPU1_SA_DQS_DN<0>
  VSS3  = GND
  DQ4_A  = M_I_CPU1_SA_DQ<4>
  VSS4  = GND
  DQ5_A  = M_I_CPU1_SA_DQ<5>
  VSS5  = GND
  DQ8_A  = M_I_CPU1_SA_DQ<8>
  VSS6  = GND
  DQ9_A  = M_I_CPU1_SA_DQ<9>
  VSS7  = GND
  DQS1_A_T  = M_I_CPU1_SA_DQS_DP<1>
  DQS1_A_C  = M_I_CPU1_SA_DQS_DN<1>
  VSS8  = GND
  DQ12_A  = M_I_CPU1_SA_DQ<12>
  VSS9  = GND
  DQ13_A  = M_I_CPU1_SA_DQ<13>
  VSS10  = GND
  DQ16_A  = M_I_CPU1_SA_DQ<16>
  VSS11  = GND
  DQ17_A  = M_I_CPU1_SA_DQ<17>
  VSS12  = GND
  DQS2_A_T  = M_I_CPU1_SA_DQS_DP<2>
  DQS2_A_C  = M_I_CPU1_SA_DQS_DN<2>
  VSS13  = GND
  DQ20_A  = M_I_CPU1_SA_DQ<20>
  VSS14  = GND
  DQ21_A  = M_I_CPU1_SA_DQ<21>
  VSS15  = GND
  DQ24_A  = M_I_CPU1_SA_DQ<24>
  VSS16  = GND
  DQ25_A  = M_I_CPU1_SA_DQ<25>
  VSS17  = GND
  DQS3_A_T  = M_I_CPU1_SA_DQS_DP<3>
  DQS3_A_C  = M_I_CPU1_SA_DQS_DN<3>
  VSS18  = GND
  DQ28_A  = M_I_CPU1_SA_DQ<28>
  VSS19  = GND
  DQ29_A  = M_I_CPU1_SA_DQ<29>
  VSS20  = GND
  CB0_A  = M_I_CPU1_SA_CB<0>
  VSS21  = GND
  CB1_A  = M_I_CPU1_SA_CB<1>
  VSS22  = GND
  DQS4_A_T  = M_I_CPU1_SA_DQS_DP<4>
  DQS4_A_C  = M_I_CPU1_SA_DQS_DN<4>
  VSS23  = GND
  CB4_A  = M_I_CPU1_SA_CB<4>
  VSS24  = GND
  CB5_A  = M_I_CPU1_SA_CB<5>
  VSS25  = GND
  ALERT_N  = M_I_CPU1_ALERT_N
  VSS26  = GND
  CS0_A_N  = M_I_CPU1_SA_CS_N<0>
  VSS27  = GND
  CA0_A  = M_I_CPU1_SA_CA<0>
  VSS28  = GND
  CA2_A  = M_I_CPU1_SA_CA<2>
  VSS29  = GND
  CA4_A  = M_I_CPU1_SA_CA<4>
  VSS30  = GND
  CA6_A  = M_I_CPU1_SA_CA<6>
  VSS31  = GND
  PAR_A  = M_I_CPU1_SA_PAR
  VSS32  = GND
  CA0_B  = M_I_CPU1_SB_CA<0>
  VSS33  = GND
  CA2_B  = M_I_CPU1_SB_CA<2>
  VSS34  = GND
  CA4_B  = M_I_CPU1_SB_CA<4>
  VSS35  = GND
  CA6_B  = M_I_CPU1_SB_CA<6>
  VSS36  = GND
  CS0_B_N  = M_I_CPU1_SB_CS_N<0>
  VSS37  = GND
  \lbd||rsp_a_n\  = M_I_CPU1_SA_RSP<0>
  \lbs||rsp_b_n\  = M_I_CPU1_SB_RSP<0>
  VSS38  = GND
  CB4_B  = M_I_CPU1_SB_CB<4>
  VSS39  = GND
  CB5_B  = M_I_CPU1_SB_CB<5>
  VSS40  = GND
  \dqs9_b_t||tdqs9_b_t||dbi4_b_n\  = M_I_CPU1_SB_DQS_DP<9>
  \dqs9_b_c||tdqs9_b_c\  = M_I_CPU1_SB_DQS_DN<9>
  VSS41  = GND
  CB0_B  = M_I_CPU1_SB_CB<0>
  VSS42  = GND
  CB1_B  = M_I_CPU1_SB_CB<1>
  VSS43  = GND
  DQ0_B  = M_I_CPU1_SB_DQ<0>
  VSS44  = GND
  DQ1_B  = M_I_CPU1_SB_DQ<1>
  VSS45  = GND
  DQS0_B_T  = M_I_CPU1_SB_DQS_DP<0>
  DQS0_B_C  = M_I_CPU1_SB_DQS_DN<0>
  VSS46  = GND
  DQ4_B  = M_I_CPU1_SB_DQ<4>
  VSS47  = GND
  DQ5_B  = M_I_CPU1_SB_DQ<5>
  VSS48  = GND
  DQ8_B  = M_I_CPU1_SB_DQ<8>
  VSS49  = GND
  DQ9_B  = M_I_CPU1_SB_DQ<9>
  VSS50  = GND
  DQS1_B_T  = M_I_CPU1_SB_DQS_DP<1>
  DQS1_B_C  = M_I_CPU1_SB_DQS_DN<1>
  VSS51  = GND
  DQ12_B  = M_I_CPU1_SB_DQ<12>
  VSS52  = GND
  DQ13_B  = M_I_CPU1_SB_DQ<13>
  VSS53  = GND
  DQ16_B  = M_I_CPU1_SB_DQ<16>
  VSS54  = GND
  DQ17_B  = M_I_CPU1_SB_DQ<17>
  VSS55  = GND
  DQS2_B_T  = M_I_CPU1_SB_DQS_DP<2>
  DQS2_B_C  = M_I_CPU1_SB_DQS_DN<2>
  VSS56  = GND
  DQ20_B  = M_I_CPU1_SB_DQ<20>
  VSS57  = GND
  DQ21_B  = M_I_CPU1_SB_DQ<21>
  VSS58  = GND
  DQ24_B  = M_I_CPU1_SB_DQ<24>
  VSS59  = GND
  DQ25_B  = M_I_CPU1_SB_DQ<25>
  VSS60  = GND
  DQS3_B_T  = M_I_CPU1_SB_DQS_DP<3>
  DQS3_B_C  = M_I_CPU1_SB_DQS_DN<3>
  VSS61  = GND
  DQ28_B  = M_I_CPU1_SB_DQ<28>
  VSS62  = GND
  DQ29_B  = M_I_CPU1_SB_DQ<29>
  VSS63  = GND
  RFU1  = NC
  VIN_BULK1  = P12V_MEM_CPU1
  VIN_BULK2  = P12V_MEM_CPU1
  \pwr_good||fail_n\  = PWRGD_CHI_CPU1_DIMM
  HAS  = PD_CHI_CPU1_DIMM_SAA
  RFU2  = NC
  RFU3  = NC
  VSS64  = GND
  DQ2_A  = M_I_CPU1_SA_DQ<2>
  VSS65  = GND
  DQ3_A  = M_I_CPU1_SA_DQ<3>
  VSS66  = GND
  \dqs5_a_c||tdqs5_a_c||dqs5_a_t||tdqs5_a_t\  = M_I_CPU1_SA_DQS_DN<5>
  \dqs5_a_t||tdqs5_a_t\  = M_I_CPU1_SA_DQS_DP<5>
  VSS67  = GND
  DQ6_A  = M_I_CPU1_SA_DQ<6>
  VSS68  = GND
  DQ7_A  = M_I_CPU1_SA_DQ<7>
  VSS69  = GND
  DQ10_A  = M_I_CPU1_SA_DQ<10>
  VSS70  = GND
  DQ11_A  = M_I_CPU1_SA_DQ<11>
  VSS71  = GND
  \dqs6_a_c||tdqs6_a_c||dqs6_a_t||tdqs6_a_t\  = M_I_CPU1_SA_DQS_DN<6>
  \dqs6_a_t||tdqs6_a_t\  = M_I_CPU1_SA_DQS_DP<6>
  VSS72  = GND
  DQ14_A  = M_I_CPU1_SA_DQ<14>
  VSS73  = GND
  DQ15_A  = M_I_CPU1_SA_DQ<15>
  VSS74  = GND
  DQ18_A  = M_I_CPU1_SA_DQ<18>
  VSS75  = GND
  DQ19_A  = M_I_CPU1_SA_DQ<19>
  VSS76  = GND
  \dqs7_a_c||tdqs7_a_c\  = M_I_CPU1_SA_DQS_DN<7>
  \dqs7_a_t||tdqs7_a_t\  = M_I_CPU1_SA_DQS_DP<7>
  VSS77  = GND
  DQ22_A  = M_I_CPU1_SA_DQ<22>
  VSS78  = GND
  DQ23_A  = M_I_CPU1_SA_DQ<23>
  VSS79  = GND
  DQ26_A  = M_I_CPU1_SA_DQ<26>
  VSS80  = GND
  DQ27_A  = M_I_CPU1_SA_DQ<27>
  VSS81  = GND
  \dqs8_a_c||tdqs8_a_c\  = M_I_CPU1_SA_DQS_DN<8>
  \dqs8_a_t||tdqs8_a_t\  = M_I_CPU1_SA_DQS_DP<8>
  VSS82  = GND
  DQ30_A  = M_I_CPU1_SA_DQ<30>
  VSS83  = GND
  DQ31_A  = M_I_CPU1_SA_DQ<31>
  VSS84  = GND
  CB2_A  = M_I_CPU1_SA_CB<2>
  VSS85  = GND
  CB3_A  = M_I_CPU1_SA_CB<3>
  VSS86  = GND
  \dqs9_a_c||tdqs9_a_c\  = M_I_CPU1_SA_DQS_DN<9>
  \dqs9_a_t||tdqs9_a_t\  = M_I_CPU1_SA_DQS_DP<9>
  VSS87  = GND
  CB6_A  = M_I_CPU1_SA_CB<6>
  VSS88  = GND
  CB7_A  = M_I_CPU1_SA_CB<7>
  VSS89  = GND
  RESET_N  = M_I_CPU1_RESET_N
  VSS90  = GND
  CS1_A_N  = M_I_CPU1_SA_CS_N<1>
  VSS91  = GND
  CA1_A  = M_I_CPU1_SA_CA<1>
  VSS92  = GND
  CA3_A  = M_I_CPU1_SA_CA<3>
  VSS93  = GND
  CA5_A  = M_I_CPU1_SA_CA<5>
  VSS94  = GND
  CK_T  = M_I_CPU1_CLK_DP<0>
  CK_C  = M_I_CPU1_CLK_DN<0>
  VSS95  = GND
  RFU4  = NC
  CA1_B  = M_I_CPU1_SB_CA<1>
  VSS96  = GND
  CA3_B  = M_I_CPU1_SB_CA<3>
  VSS97  = GND
  CA5_B  = M_I_CPU1_SB_CA<5>
  VSS98  = GND
  PAR_B  = M_I_CPU1_SB_PAR
  VSS99  = GND
  CS1_B_N  = M_I_CPU1_SB_CS_N<1>
  VSS100  = GND
  RFU5  = NC
  RFU6  = NC
  VSS101  = GND
  CB6_B  = M_I_CPU1_SB_CB<6>
  VSS102  = GND
  CB7_B  = M_I_CPU1_SB_CB<7>
  VSS103  = GND
  DQS4_B_C  = M_I_CPU1_SB_DQS_DN<4>
  DQS4_B_T  = M_I_CPU1_SB_DQS_DP<4>
  VSS104  = GND
  CB2_B  = M_I_CPU1_SB_CB<2>
  VSS105  = GND
  CB3_B  = M_I_CPU1_SB_CB<3>
  VSS106  = GND
  DQ2_B  = M_I_CPU1_SB_DQ<2>
  VSS107  = GND
  DQ3_B  = M_I_CPU1_SB_DQ<3>
  VSS108  = GND
  \dqs5_b_c||tdqs5_b_c\  = M_I_CPU1_SB_DQS_DN<5>
  \dqs5_b_t||tdqs5_b_t\  = M_I_CPU1_SB_DQS_DP<5>
  VSS109  = GND
  DQ6_B  = M_I_CPU1_SB_DQ<6>
  VSS110  = GND
  DQ7_B  = M_I_CPU1_SB_DQ<7>
  VSS111  = GND
  DQ10_B  = M_I_CPU1_SB_DQ<10>
  VSS112  = GND
  DQ11_B  = M_I_CPU1_SB_DQ<11>
  VSS113  = GND
  \dqs6_b_c||tdqs6_b_c\  = M_I_CPU1_SB_DQS_DN<6>
  \dqs6_b_t||tdqs6_b_t\  = M_I_CPU1_SB_DQS_DP<6>
  VSS114  = GND
  DQ14_B  = M_I_CPU1_SB_DQ<14>
  VSS115  = GND
  DQ15_B  = M_I_CPU1_SB_DQ<15>
  VSS116  = GND
  DQ18_B  = M_I_CPU1_SB_DQ<18>
  VSS117  = GND
  DQ19_B  = M_I_CPU1_SB_DQ<19>
  VSS118  = GND
  \dqs7_b_c||tdqs7_b_c\  = M_I_CPU1_SB_DQS_DN<7>
  \dqs7_b_t||tdqs7_b_t\  = M_I_CPU1_SB_DQS_DP<7>
  VSS119  = GND
  DQ22_B  = M_I_CPU1_SB_DQ<22>
  VSS120  = GND
  DQ23_B  = M_I_CPU1_SB_DQ<23>
  VSS121  = GND
  DQ26_B  = M_I_CPU1_SB_DQ<26>
  VSS122  = GND
  DQ27_B  = M_I_CPU1_SB_DQ<27>
  VSS123  = GND
  \dqs8_b_c||tdqs8_b_c\  = M_I_CPU1_SB_DQS_DN<8>
  \dqs8_b_t||tdqs8_b_t\  = M_I_CPU1_SB_DQS_DP<8>
  VSS124  = GND
  DQ30_B  = M_I_CPU1_SB_DQ<30>
  VSS125  = GND
  DQ31_B  = M_I_CPU1_SB_DQ<31>
  VSS126  = GND
  G1  = GND
  G2  = GND
  G3  = GND

(kicad_pcb
	(version 20260206)
	(generator "pcbnew")
	(generator_version "10.0")
	(general
		(thickness 1.6)
		(legacy_teardrops no)
	)
	(paper "A4")
	(title_block
		(title "04192023_DAF0TMB3IC0_F0TG_MB_C_brd_V02_OCP.brd")
		(comment 1 "Grand Teton / footprint 230 of 8354 (J100), pads 1-46 of 291")
	)
	(layers
		(0 "F.Cu" signal "TOP")
		(4 "In1.Cu" signal "GND")
		(6 "In2.Cu" signal "IN1")
		(8 "In3.Cu" signal "GND1")
		(10 "In4.Cu" signal "IN2")
		(12 "In5.Cu" signal "GND2")
		(14 "In6.Cu" signal "IN3")
		(16 "In7.Cu" signal "GND3")
		(18 "In8.Cu" signal "VCC")
		(20 "In9.Cu" signal "VCC1")
		(22 "In10.Cu" signal "GND4")
		(24 "In11.Cu" signal "IN4")
		(26 "In12.Cu" signal "GND5")
		(28 "In13.Cu" signal "IN5")
		(30 "In14.Cu" signal "GND6")
		(32 "In15.Cu" signal "IN6")
		(34 "In16.Cu" signal "GND7")
		(2 "B.Cu" signal "BOTTOM")
		(9 "F.Adhes" user "F.Adhesive")
		(11 "B.Adhes" user "B.Adhesive")
		(13 "F.Paste" user "Package Geometry/Pastemask Top")
		(15 "B.Paste" user "Package Geometry/Pastemask Bottom")
		(5 "F.SilkS" user "Ref Des/Silkscreen Top")
		(7 "B.SilkS" user "Ref Des/Silkscreen Bottom")
		(1 "F.Mask" user "Board Geometry/Soldermask Top")
		(3 "B.Mask" user "Board Geometry/Soldermask Bottom")
		(17 "Dwgs.User" user "User.Drawings")
		(19 "Cmts.User" user "User.Comments")
		(21 "Eco1.User" user "User.Eco1")
		(23 "Eco2.User" user "User.Eco2")
		(25 "Edge.Cuts" user "Board Geometry/Outline")
		(27 "Margin" user)
		(31 "F.CrtYd" user "Package Geometry/Place Bound Top")
		(29 "B.CrtYd" user "Package Geometry/Place Bound Bottom")
		(35 "F.Fab" user "Ref Des/Assembly Top")
		(33 "B.Fab" user "Ref Des/Assembly Bottom")
	)
	(footprint ""
		(layer "F.Cu")
		(at 181.566058 -255.560322 180)
		(property "Reference" "J100"
			(at -2.7178 -81.857088 0)
			(unlocked yes)
			(layer "F.SilkS")
			(effects
				(font
					(size 0.7874 0.5842)
					(thickness 0.1524)
				)
			)
		)
		(property "Value" ""
			(at 0 0 180)
			(layer "F.Fab")
			(effects
				(font
					(size 1.27 1.27)
				)
			)
		)
		(duplicate_pad_numbers_are_jumpers no)
		(pad "1" smd rect
			(at -2.050034 -63.324994 90)
			(size 0.519938 1.4986)
			(layers "F.Cu" "F.Mask" "F.Paste")
			(net "P12V_MEM_CPU1")
		)
		(pad "2" smd rect
			(at -2.050034 -62.47511 90)
			(size 0.519938 1.4986)
			(layers "F.Cu" "F.Mask" "F.Paste")
			(net "Net_2368")
		)
		(pad "3" smd rect
			(at -2.050034 -61.624972 90)
			(size 0.519938 1.4986)
			(layers "F.Cu" "F.Mask" "F.Paste")
			(net "P3V3_AUX")
		)
		(pad "4" smd rect
			(at -2.050034 -60.775088 90)
			(size 0.519938 1.4986)
			(layers "F.Cu" "F.Mask" "F.Paste")
			(net "I3C_SPD_DDRI_CPU1_SCL")
		)
		(pad "5" smd rect
			(at -2.050034 -59.92495 90)
			(size 0.519938 1.4986)
			(layers "F.Cu" "F.Mask" "F.Paste")
			(net "I3C_SPD_DDRI_CPU1_SDA")
		)
		(pad "6" smd rect
			(at -2.050034 -59.075066 90)
			(size 0.519938 1.4986)
			(layers "F.Cu" "F.Mask" "F.Paste")
			(net "GND")
		)
		(pad "7" smd rect
			(at -2.050034 -58.224928 90)
			(size 0.519938 1.4986)
			(layers "F.Cu" "F.Mask" "F.Paste")
			(net "M_I_CPU1_SA_DQ<0>")
		)
		(pad "8" smd rect
			(at -2.050034 -57.375044 90)
			(size 0.519938 1.4986)
			(layers "F.Cu" "F.Mask" "F.Paste")
			(net "GND")
		)
		(pad "9" smd rect
			(at -2.050034 -56.524906 90)
			(size 0.519938 1.4986)
			(layers "F.Cu" "F.Mask" "F.Paste")
			(net "M_I_CPU1_SA_DQ<1>")
		)
		(pad "10" smd rect
			(at -2.050034 -55.675022 90)
			(size 0.519938 1.4986)
			(layers "F.Cu" "F.Mask" "F.Paste")
			(net "GND")
		)
		(pad "11" smd rect
			(at -2.050034 -54.824884 90)
			(size 0.519938 1.4986)
			(layers "F.Cu" "F.Mask" "F.Paste")
			(net "M_I_CPU1_SA_DQS_DP<0>")
		)
		(pad "12" smd rect
			(at -2.050034 -53.975 90)
			(size 0.519938 1.4986)
			(layers "F.Cu" "F.Mask" "F.Paste")
			(net "M_I_CPU1_SA_DQS_DN<0>")
		)
		(pad "13" smd rect
			(at -2.050034 -53.125116 90)
			(size 0.519938 1.4986)
			(layers "F.Cu" "F.Mask" "F.Paste")
			(net "GND")
		)
		(pad "14" smd rect
			(at -2.050034 -52.274978 90)
			(size 0.519938 1.4986)
			(layers "F.Cu" "F.Mask" "F.Paste")
			(net "M_I_CPU1_SA_DQ<4>")
		)
		(pad "15" smd rect
			(at -2.050034 -51.425094 90)
			(size 0.519938 1.4986)
			(layers "F.Cu" "F.Mask" "F.Paste")
			(net "GND")
		)
		(pad "16" smd rect
			(at -2.050034 -50.574956 90)
			(size 0.519938 1.4986)
			(layers "F.Cu" "F.Mask" "F.Paste")
			(net "M_I_CPU1_SA_DQ<5>")
		)
		(pad "17" smd rect
			(at -2.050034 -49.725072 90)
			(size 0.519938 1.4986)
			(layers "F.Cu" "F.Mask" "F.Paste")
			(net "GND")
		)
		(pad "18" smd rect
			(at -2.050034 -48.874934 90)
			(size 0.519938 1.4986)
			(layers "F.Cu" "F.Mask" "F.Paste")
			(net "M_I_CPU1_SA_DQ<8>")
		)
		(pad "19" smd rect
			(at -2.050034 -48.02505 90)
			(size 0.519938 1.4986)
			(layers "F.Cu" "F.Mask" "F.Paste")
			(net "GND")
		)
		(pad "20" smd rect
			(at -2.050034 -47.174912 90)
			(size 0.519938 1.4986)
			(layers "F.Cu" "F.Mask" "F.Paste")
			(net "M_I_CPU1_SA_DQ<9>")
		)
		(pad "21" smd rect
			(at -2.050034 -46.325028 90)
			(size 0.519938 1.4986)
			(layers "F.Cu" "F.Mask" "F.Paste")
			(net "GND")
		)
		(pad "22" smd rect
			(at -2.050034 -45.47489 90)
			(size 0.519938 1.4986)
			(layers "F.Cu" "F.Mask" "F.Paste")
			(net "M_I_CPU1_SA_DQS_DP<1>")
		)
		(pad "23" smd rect
			(at -2.050034 -44.625006 90)
			(size 0.519938 1.4986)
			(layers "F.Cu" "F.Mask" "F.Paste")
			(net "M_I_CPU1_SA_DQS_DN<1>")
		)
		(pad "24" smd rect
			(at -2.050034 -43.775122 90)
			(size 0.519938 1.4986)
			(layers "F.Cu" "F.Mask" "F.Paste")
			(net "GND")
		)
		(pad "25" smd rect
			(at -2.050034 -42.924984 90)
			(size 0.519938 1.4986)
			(layers "F.Cu" "F.Mask" "F.Paste")
			(net "M_I_CPU1_SA_DQ<12>")
		)
		(pad "26" smd rect
			(at -2.050034 -42.0751 90)
			(size 0.519938 1.4986)
			(layers "F.Cu" "F.Mask" "F.Paste")
			(net "GND")
		)
		(pad "27" smd rect
			(at -2.050034 -41.224962 90)
			(size 0.519938 1.4986)
			(layers "F.Cu" "F.Mask" "F.Paste")
			(net "M_I_CPU1_SA_DQ<13>")
		)
		(pad "28" smd rect
			(at -2.050034 -40.375078 90)
			(size 0.519938 1.4986)
			(layers "F.Cu" "F.Mask" "F.Paste")
			(net "GND")
		)
		(pad "29" smd rect
			(at -2.050034 -39.52494 90)
			(size 0.519938 1.4986)
			(layers "F.Cu" "F.Mask" "F.Paste")
			(net "M_I_CPU1_SA_DQ<16>")
		)
		(pad "30" smd rect
			(at -2.050034 -38.675056 90)
			(size 0.519938 1.4986)
			(layers "F.Cu" "F.Mask" "F.Paste")
			(net "GND")
		)
		(pad "31" smd rect
			(at -2.050034 -37.824918 90)
			(size 0.519938 1.4986)
			(layers "F.Cu" "F.Mask" "F.Paste")
			(net "M_I_CPU1_SA_DQ<17>")
		)
		(pad "32" smd rect
			(at -2.050034 -36.975034 90)
			(size 0.519938 1.4986)
			(layers "F.Cu" "F.Mask" "F.Paste")
			(net "GND")
		)
		(pad "33" smd rect
			(at -2.050034 -36.124896 90)
			(size 0.519938 1.4986)
			(layers "F.Cu" "F.Mask" "F.Paste")
			(net "M_I_CPU1_SA_DQS_DP<2>")
		)
		(pad "34" smd rect
			(at -2.050034 -35.275012 90)
			(size 0.519938 1.4986)
			(layers "F.Cu" "F.Mask" "F.Paste")
			(net "M_I_CPU1_SA_DQS_DN<2>")
		)
		(pad "35" smd rect
			(at -2.050034 -34.425128 90)
			(size 0.519938 1.4986)
			(layers "F.Cu" "F.Mask" "F.Paste")
			(net "GND")
		)
		(pad "36" smd rect
			(at -2.050034 -33.57499 90)
			(size 0.519938 1.4986)
			(layers "F.Cu" "F.Mask" "F.Paste")
			(net "M_I_CPU1_SA_DQ<20>")
		)
		(pad "37" smd rect
			(at -2.050034 -32.725106 90)
			(size 0.519938 1.4986)
			(layers "F.Cu" "F.Mask" "F.Paste")
			(net "GND")
		)
		(pad "38" smd rect
			(at -2.050034 -31.874968 90)
			(size 0.519938 1.4986)
			(layers "F.Cu" "F.Mask" "F.Paste")
			(net "M_I_CPU1_SA_DQ<21>")
		)
		(pad "39" smd rect
			(at -2.050034 -31.025084 90)
			(size 0.519938 1.4986)
			(layers "F.Cu" "F.Mask" "F.Paste")
			(net "GND")
		)
		(pad "40" smd rect
			(at -2.050034 -30.174946 90)
			(size 0.519938 1.4986)
			(layers "F.Cu" "F.Mask" "F.Paste")
			(net "M_I_CPU1_SA_DQ<24>")
		)
		(pad "41" smd rect
			(at -2.050034 -29.325062 90)
			(size 0.519938 1.4986)
			(layers "F.Cu" "F.Mask" "F.Paste")
			(net "GND")
		)
		(pad "42" smd rect
			(at -2.050034 -28.474924 90)
			(size 0.519938 1.4986)
			(layers "F.Cu" "F.Mask" "F.Paste")
			(net "M_I_CPU1_SA_DQ<25>")
		)
		(pad "43" smd rect
			(at -2.050034 -27.62504 90)
			(size 0.519938 1.4986)
			(layers "F.Cu" "F.Mask" "F.Paste")
			(net "GND")
		)
		(pad "44" smd rect
			(at -2.050034 -26.774902 90)
			(size 0.519938 1.4986)
			(layers "F.Cu" "F.Mask" "F.Paste")
			(net "M_I_CPU1_SA_DQS_DP<3>")
		)
		(pad "45" smd rect
			(at -2.050034 -25.925018 90)
			(size 0.519938 1.4986)
			(layers "F.Cu" "F.Mask" "F.Paste")
			(net "M_I_CPU1_SA_DQS_DN<3>")
		)
		(pad "46" smd rect
			(at -2.050034 -25.07488 90)
			(size 0.519938 1.4986)
			(layers "F.Cu" "F.Mask" "F.Paste")
			(net "GND")
		)
	)
)
